# BASEBOARD_FAB2 (Tioga Pass) — schematic netlist excerpt (pin names and nets, part order shuffled) for the footprints in the layout excerpt that follows; sources: Cadence DE-HDL packaged netlist, KiCad conversion of Wiwynn_Tioga_Pass_MB.brd

R1U12  RES  51 5.0% CHIP  pkg 0402  page 144 : A = SGPIO_BMC_LD_R_N ; B = SGPIO_BMC_LD_N
C2G6  CAP_A  47UF 4V 20% X5R  pkg 0603V  page 225 : A = PVDDQ_GHJ ; B = GND
R9G22  RES  0.0 5% CHIP  pkg 0402  page 141 : A = NIC_MDI_SPRV_RJ45_0_DN ; B = NIC_MDI_SPRV_RJ45_0_R_DN

(kicad_pcb
	(version 20260206)
	(generator "pcbnew")
	(generator_version "10.0")
	(general
		(thickness 1.6)
		(legacy_teardrops no)
	)
	(paper "A4")
	(title_block
		(title "Wiwynn_Tioga_Pass_MB.brd")
		(comment 1 "Tioga Pass / footprints 31-33 of 4770")
	)
	(layers
		(0 "F.Cu" signal "TOP")
		(4 "In1.Cu" signal "L2GND")
		(6 "In2.Cu" signal "L3")
		(8 "In3.Cu" signal "L4GND")
		(10 "In4.Cu" signal "L5")
		(12 "In5.Cu" signal "L6GND")
		(14 "In6.Cu" signal "L7VCC")
		(16 "In7.Cu" signal "L8VCC")
		(18 "In8.Cu" signal "L9GND")
		(20 "In9.Cu" signal "L10")
		(22 "In10.Cu" signal "L11GND")
		(24 "In11.Cu" signal "L12")
		(26 "In12.Cu" signal "L13GND")
		(2 "B.Cu" signal "BOTTOM")
		(9 "F.Adhes" user "F.Adhesive")
		(11 "B.Adhes" user "B.Adhesive")
		(13 "F.Paste" user "Package Geometry/Pastemask Top")
		(15 "B.Paste" user "Package Geometry/Pastemask Bottom")
		(5 "F.SilkS" user "Ref Des/Silkscreen Top")
		(7 "B.SilkS" user "Ref Des/Silkscreen Bottom")
		(1 "F.Mask" user "Board Geometry/Soldermask Top")
		(3 "B.Mask" user "Board Geometry/Soldermask Bottom")
		(17 "Dwgs.User" user "User.Drawings")
		(19 "Cmts.User" user "User.Comments")
		(21 "Eco1.User" user "User.Eco1")
		(23 "Eco2.User" user "User.Eco2")
		(25 "Edge.Cuts" user "Board Geometry/Outline")
		(27 "Margin" user)
		(31 "F.CrtYd" user "Package Geometry/Place Bound Top")
		(29 "B.CrtYd" user "Package Geometry/Place Bound Bottom")
		(35 "F.Fab" user "Ref Des/Assembly Top")
		(33 "B.Fab" user "Ref Des/Assembly Bottom")
	)
	(footprint ""
		(layer "F.Cu")
		(at 415.671 -23.114)
		(property "Reference" "R1U12"
			(at 0 0 0)
			(layer "F.SilkS")
			(hide yes)
			(effects
				(font
					(size 1.27 1.27)
				)
			)
		)
		(property "Value" ""
			(at 0 0 0)
			(layer "F.Fab")
			(effects
				(font
					(size 1.27 1.27)
				)
			)
		)
		(duplicate_pad_numbers_are_jumpers no)
		(fp_poly
			(pts
				(xy -0.2794 -0.1016) (xy 0.2794 -0.1016) (xy 0.2794 0.9906) (xy -0.2794 0.9906)
			)
			(stroke
				(width 0)
				(type default)
			)
			(fill no)
			(layer "F.CrtYd")
		)
		(fp_line
			(start -0.2794 -0.1016)
			(end -0.2794 0.9906)
			(stroke
				(width 0.1)
				(type default)
			)
			(layer "F.Fab")
		)
		(fp_line
			(start -0.2794 0.9906)
			(end 0.2794 0.9906)
			(stroke
				(width 0.1)
				(type default)
			)
			(layer "F.Fab")
		)
		(fp_line
			(start 0.2794 -0.1016)
			(end -0.2794 -0.1016)
			(stroke
				(width 0.1)
				(type default)
			)
			(layer "F.Fab")
		)
		(fp_line
			(start 0.2794 0.9906)
			(end 0.2794 -0.1016)
			(stroke
				(width 0.1)
				(type default)
			)
			(layer "F.Fab")
		)
		(pad "1" smd rect
			(at 0 0)
			(size 0.508 0.508)
			(layers "F.Cu" "F.Mask" "F.Paste")
			(net "SGPIO_BMC_LD_R_N")
		)
		(pad "2" smd rect
			(at 0 0.889)
			(size 0.508 0.508)
			(layers "F.Cu" "F.Mask" "F.Paste")
			(net "SGPIO_BMC_LD_N")
		)
		(zone
			(layer "F.Cu")
			(hatch none 0.5)
			(connect_pads
				(clearance 0)
			)
			(min_thickness 0.25)
			(keepout
				(tracks allowed)
				(vias not_allowed)
				(pads allowed)
				(copperpour not_allowed)
				(footprints allowed)
			)
			(placement
				(enabled no)
				(sheetname "")
			)
			(fill
				(thermal_gap 0.5)
				(thermal_bridge_width 0.5)
				(island_removal_mode 0)
			)
			(polygon
				(pts
					(xy 415.417 -22.86) (xy 415.925 -22.86) (xy 415.925 -22.479) (xy 415.417 -22.479)
				)
			)
		)
		(zone
			(layer "F.Cu")
			(hatch none 0.5)
			(connect_pads
				(clearance 0)
			)
			(min_thickness 0.25)
			(keepout
				(tracks not_allowed)
				(vias allowed)
				(pads allowed)
				(copperpour not_allowed)
				(footprints allowed)
			)
			(placement
				(enabled no)
				(sheetname "")
			)
			(fill
				(thermal_gap 0.5)
				(thermal_bridge_width 0.5)
				(island_removal_mode 0)
			)
			(polygon
				(pts
					(xy 415.417 -22.479) (xy 415.925 -22.479) (xy 415.925 -22.86) (xy 415.417 -22.86)
				)
			)
		)
	)
	(footprint ""
		(layer "F.Cu")
		(at 477.68002 -12.474194)
		(property "Reference" "R9G22"
			(at -0.8382 -0.67818 0)
			(unlocked yes)
			(layer "F.SilkS")
			(effects
				(font
					(size 0.4064 0.254)
					(thickness 0.1524)
				)
				(justify left)
			)
		)
		(property "Value" ""
			(at 0 0 0)
			(layer "F.Fab")
			(effects
				(font
					(size 1.27 1.27)
				)
			)
		)
		(duplicate_pad_numbers_are_jumpers no)
		(fp_poly
			(pts
				(xy -0.2794 -0.1016) (xy 0.2794 -0.1016) (xy 0.2794 0.9906) (xy -0.2794 0.9906)
			)
			(stroke
				(width 0)
				(type default)
			)
			(fill no)
			(layer "F.CrtYd")
		)
		(fp_line
			(start -0.2794 -0.1016)
			(end -0.2794 0.9906)
			(stroke
				(width 0.1)
				(type default)
			)
			(layer "F.Fab")
		)
		(fp_line
			(start -0.2794 0.9906)
			(end 0.2794 0.9906)
			(stroke
				(width 0.1)
				(type default)
			)
			(layer "F.Fab")
		)
		(fp_line
			(start 0.2794 -0.1016)
			(end -0.2794 -0.1016)
			(stroke
				(width 0.1)
				(type default)
			)
			(layer "F.Fab")
		)
		(fp_line
			(start 0.2794 0.9906)
			(end 0.2794 -0.1016)
			(stroke
				(width 0.1)
				(type default)
			)
			(layer "F.Fab")
		)
		(pad "1" smd rect
			(at 0 0)
			(size 0.508 0.508)
			(layers "F.Cu" "F.Mask" "F.Paste")
			(net "NIC_MDI_SPRV_RJ45_0_DN")
		)
		(pad "2" smd rect
			(at 0 0.889)
			(size 0.508 0.508)
			(layers "F.Cu" "F.Mask" "F.Paste")
			(net "NIC_MDI_SPRV_RJ45_0_R_DN")
		)
		(zone
			(layer "F.Cu")
			(hatch none 0.5)
			(connect_pads
				(clearance 0)
			)
			(min_thickness 0.25)
			(keepout
				(tracks allowed)
				(vias not_allowed)
				(pads allowed)
				(copperpour not_allowed)
				(footprints allowed)
			)
			(placement
				(enabled no)
				(sheetname "")
			)
			(fill
				(thermal_gap 0.5)
				(thermal_bridge_width 0.5)
				(island_removal_mode 0)
			)
			(polygon
				(pts
					(xy 477.42602 -12.220194) (xy 477.93402 -12.220194) (xy 477.93402 -11.839194) (xy 477.42602 -11.839194)
				)
			)
		)
		(zone
			(layer "F.Cu")
			(hatch none 0.5)
			(connect_pads
				(clearance 0)
			)
			(min_thickness 0.25)
			(keepout
				(tracks not_allowed)
				(vias allowed)
				(pads allowed)
				(copperpour not_allowed)
				(footprints allowed)
			)
			(placement
				(enabled no)
				(sheetname "")
			)
			(fill
				(thermal_gap 0.5)
				(thermal_bridge_width 0.5)
				(island_removal_mode 0)
			)
			(polygon
				(pts
					(xy 477.42602 -11.839194) (xy 477.93402 -11.839194) (xy 477.93402 -12.220194) (xy 477.42602 -12.220194)
				)
			)
		)
	)
	(footprint ""
		(layer "F.Cu")
		(at 104.5591 -12.954 90)
		(property "Reference" "C2G6"
			(at 1.848866 0.752348 90)
			(unlocked yes)
			(layer "F.SilkS")
			(effects
				(font
					(size 1.27 0.9652)
					(thickness 0.1524)
				)
			)
		)
		(property "Value" ""
			(at 0 0 90)
			(layer "F.Fab")
			(effects
				(font
					(size 1.27 1.27)
				)
			)
		)
		(duplicate_pad_numbers_are_jumpers no)
		(fp_rect
			(start -0.500126 1.598422)
			(end 0.500126 -0.201422)
			(stroke
				(width 0)
				(type default)
			)
			(fill no)
			(layer "F.CrtYd")
		)
		(fp_line
			(start 0.500126 -0.201422)
			(end 0.500126 1.598422)
			(stroke
				(width 0.1)
				(type default)
			)
			(layer "F.Fab")
		)
		(fp_line
			(start -0.500126 -0.201422)
			(end 0.500126 -0.201422)
			(stroke
				(width 0.1)
				(type default)
			)
			(layer "F.Fab")
		)
		(fp_line
			(start 0.500126 1.598422)
			(end -0.500126 1.598422)
			(stroke
				(width 0.1)
				(type default)
			)
			(layer "F.Fab")
		)
		(fp_line
			(start -0.500126 1.598422)
			(end -0.500126 -0.201422)
			(stroke
				(width 0.1)
				(type default)
			)
			(layer "F.Fab")
		)
		(pad "1" smd rect
			(at 0 0)
			(size 0.889 0.9906)
			(layers "F.Cu" "F.Mask" "F.Paste")
			(net "PVDDQ_GHJ")
		)
		(pad "2" smd rect
			(at 0 1.397)
			(size 0.889 0.9906)
			(layers "F.Cu" "F.Mask" "F.Paste")
			(net "GND")
		)
		(zone
			(layer "F.Cu")
			(hatch none 0.5)
			(connect_pads
				(clearance 0)
			)
			(min_thickness 0.25)
			(keepout
				(tracks allowed)
				(vias not_allowed)
				(pads allowed)
				(copperpour not_allowed)
				(footprints allowed)
			)
			(placement
				(enabled no)
				(sheetname "")
			)
			(fill
				(thermal_gap 0.5)
				(thermal_bridge_width 0.5)
				(island_removal_mode 0)
			)
			(polygon
				(pts
					(xy 105.5116 -12.4587) (xy 105.5116 -13.4493) (xy 105.0036 -13.4493) (xy 105.0036 -12.4587)
				)
			)
		)
		(zone
			(layer "F.Cu")
			(hatch none 0.5)
			(connect_pads
				(clearance 0)
			)
			(min_thickness 0.25)
			(keepout
				(tracks not_allowed)
				(vias allowed)
				(pads allowed)
				(copperpour not_allowed)
				(footprints allowed)
			)
			(placement
				(enabled no)
				(sheetname "")
			)
			(fill
				(thermal_gap 0.5)
				(thermal_bridge_width 0.5)
				(island_removal_mode 0)
			)
			(polygon
				(pts
					(xy 105.5116 -12.4587) (xy 105.5116 -13.4493) (xy 105.0036 -13.4493) (xy 105.0036 -12.4587)
				)
			)
		)
	)
)
